FILE_TYPE = MACRO_DRAWING;
SET COLOR_WIRE YELLOW;
SET COLOR_PROP ORANGE;
SET COLOR_DOT WHITE;
SET COLOR_ARC YELLOW;
SET COLOR_BODY GREEN;
SET COLOR_NOTE PURPLE;
SET PROP_DISPLAY VALUE;
SET PAGE_NUMBER P77;
FORCEADD Q_RES..2
R 2
(-5900 3950);
FORCEPROP 1 LAST LOCATION R702
J 2
(-5925 4100);
DISPLAY 0.489362 (-5925 4100);
PAINT SKYBLUE (-5925 4100);
FORCEPROP 0 LAST $SEC 1
J 0
(-5925 4125);
DISPLAY 0.680851 (-5925 4125);
PAINT MONO (-5925 4125);
DISPLAY INVISIBLE (-5925 4125);
FORCEPROP 0 LAST CDS_SEC 1
J 0
(-5925 4125);
DISPLAY 1.021277 (-5925 4125);
DISPLAY INVISIBLE (-5925 4125);
FORCEPROP 1 LASTPIN (-5900 4050) $PN 1
J 2
(-5905 4012);
DISPLAY 0.489362 (-5905 4012);
PAINT MONO (-5905 4012);
FORCEPROP 1 LASTPIN (-5900 3850) $PN 2
J 2
(-5905 3860);
DISPLAY 0.489362 (-5905 3860);
PAINT MONO (-5905 3860);
FORCEPROP 1 LAST PACK_TYPE 0402LF
J 2
(-5940 3850);
DISPLAY 0.489362 (-5940 3850);
PAINT SKYBLUE (-5940 3850);
FORCEPROP 1 LAST VALUE 10K
J 2
(-5945 4050);
DISPLAY 0.489362 (-5945 4050);
PAINT SKYBLUE (-5945 4050);
FORCEPROP 1 LAST TOLERANCE 5%
J 2
(-5945 4000);
DISPLAY 0.489362 (-5945 4000);
PAINT SKYBLUE (-5945 4000);
FORCEPROP 1 LAST MATERIAL EMPTY
J 2
(-5940 3900);
DISPLAY 0.489362 (-5940 3900);
PAINT RED (-5940 3900);
FORCEPROP 1 LAST WATTAGE 1/16W
J 2
(-5940 3950);
DISPLAY 0.489362 (-5940 3950);
PAINT SKYBLUE (-5940 3950);
FORCEPROP 2 LAST CDS_LIB pure_quanta
J 2
(-5900 3950);
DISPLAY INVISIBLE (-5900 3950);
FORCEPROP 1 LAST PATH I1
J 2
(-5950 4125);
DISPLAY 0.978723 (-5950 4125);
PAINT WHITE (-5950 4125);
DISPLAY INVISIBLE (-5950 4125);
FORCEPROP 1 LAST PART_NUMBER CS31002JB08
J 2
(-5950 3800);
DISPLAY 0.489362 (-5950 3800);
PAINT SKYBLUE (-5950 3800);
DISPLAY INVISIBLE (-5950 3800);
FORCEADD UNIVERSAL_GND..1
(-4125 4375);
FORCEPROP 3 LASTPIN (-4125 4425) SIG_NAME GND\g
J 0
(-4115 4435);
DISPLAY 0.659574 (-4115 4435);
PAINT MONO (-4115 4435);
DISPLAY INVISIBLE (-4115 4435);
FORCEPROP 2 LAST CDS_LIB pure_quanta_power
J 0
(-4125 4375);
DISPLAY INVISIBLE (-4125 4375);
FORCEPROP 1 LAST HDL_POWER GND
J 1
(-4100 4300);
DISPLAY 0.872340 (-4100 4300);
PAINT GREEN (-4100 4300);
DISPLAY INVISIBLE (-4100 4300);
FORCEPROP 1 LAST PATH I10
J 0
(-4050 4375);
DISPLAY 0.872340 (-4050 4375);
PAINT AQUA (-4050 4375);
DISPLAY INVISIBLE (-4050 4375);
FORCEADD Q_CAP..1
(-4125 4575);
FORCEPROP 1 LAST LOCATION C223
J 0
(-4075 4725);
DISPLAY 0.489362 (-4075 4725);
PAINT SKYBLUE (-4075 4725);
FORCEPROP 2 LAST $SEC 1
J 0
(-4075 4775);
DISPLAY 0.680851 (-4075 4775);
PAINT MONO (-4075 4775);
DISPLAY INVISIBLE (-4075 4775);
FORCEPROP 2 LAST CDS_SEC 1
J 0
(-4075 4775);
DISPLAY 0.680851 (-4075 4775);
DISPLAY INVISIBLE (-4075 4775);
FORCEPROP 1 LASTPIN (-4125 4675) $PN 1
J 0
(-4115 4655);
DISPLAY 0.489362 (-4115 4655);
PAINT MONO (-4115 4655);
FORCEPROP 1 LASTPIN (-4125 4475) $PN 2
J 0
(-4115 4455);
DISPLAY 0.489362 (-4115 4455);
PAINT MONO (-4115 4455);
FORCEPROP 1 LAST MATERIAL X7R
J 0
(-4075 4525);
DISPLAY 0.489362 (-4075 4525);
PAINT SKYBLUE (-4075 4525);
FORCEPROP 1 LAST TOLERANCE 10%
J 0
(-4075 4575);
DISPLAY 0.489362 (-4075 4575);
PAINT SKYBLUE (-4075 4575);
FORCEPROP 1 LAST PACK_TYPE 0402
J 0
(-4075 4475);
DISPLAY 0.489362 (-4075 4475);
PAINT SKYBLUE (-4075 4475);
FORCEPROP 1 LAST VOLTAGE 25V
J 0
(-4075 4625);
DISPLAY 0.489362 (-4075 4625);
PAINT SKYBLUE (-4075 4625);
FORCEPROP 1 LAST VALUE 0.1UF
J 0
(-4075 4675);
DISPLAY 0.489362 (-4075 4675);
PAINT SKYBLUE (-4075 4675);
FORCEPROP 2 LAST CDS_LIB pure_quanta
J 0
(-4125 4575);
DISPLAY INVISIBLE (-4125 4575);
FORCEPROP 1 LAST PATH I11
J 0
(-4075 4725);
DISPLAY 0.978723 (-4075 4725);
PAINT WHITE (-4075 4725);
DISPLAY INVISIBLE (-4075 4725);
FORCEPROP 1 LAST PART_NUMBER CH4104K1B00
J 0
(-4075 4425);
DISPLAY 0.489362 (-4075 4425);
PAINT SKYBLUE (-4075 4425);
DISPLAY INVISIBLE (-4075 4425);
FORCEADD UNIVERSAL_POWER..1
R 2
(-4200 4900);
FORCEPROP 3 LASTPIN (-4200 4850) SIG_NAME P1V8_AUX\g
J 0
(-4190 4860);
DISPLAY 0.659574 (-4190 4860);
PAINT MONO (-4190 4860);
DISPLAY INVISIBLE (-4190 4860);
FORCEPROP 1 LAST HDL_POWER P1V8_AUX
J 1
(-4200 4950);
DISPLAY 0.489362 (-4200 4950);
PAINT GREEN (-4200 4950);
FORCEPROP 2 LAST CDS_LIB pure_quanta_power
J 0
(-4200 4900);
DISPLAY INVISIBLE (-4200 4900);
FORCEPROP 1 LAST PATH I12
J 2
(-4250 4925);
DISPLAY 0.872340 (-4250 4925);
PAINT AQUA (-4250 4925);
DISPLAY INVISIBLE (-4250 4925);
FORCEADD OFFPAGE..5
R 2
(-3375 4225);
FORCEPROP 2 LAST $XR0 200 
J 0
(-3186 4225);
DISPLAY 0.638298 (-3186 4225);
PAINT MONO (-3186 4225);
FORCEPROP 2 LAST CDS_LIB standard
J 0
(-3375 4225);
DISPLAY INVISIBLE (-3375 4225);
FORCEPROP 2 LAST BOM_COST SYS_CLOCK
J 2
(-3575 4325);
DISPLAY 0.808511 (-3575 4325);
DISPLAY INVISIBLE (-3575 4325);
FORCEPROP 2 LAST ROOM DB2000_2_NVME
J 2
(-3575 4275);
DISPLAY 0.808511 (-3575 4275);
PAINT RED (-3575 4275);
DISPLAY INVISIBLE (-3575 4275);
FORCEPROP 1 LAST OFFPAGE TRUE
J 2
(-3700 4100);
DISPLAY 0.872340 (-3700 4100);
PAINT GREEN (-3700 4100);
DISPLAY INVISIBLE (-3700 4100);
FORCEPROP 1 LAST COMMENT_BODY TRUE
J 2
(-3475 4150);
DISPLAY 0.872340 (-3475 4150);
PAINT GREEN (-3475 4150);
DISPLAY INVISIBLE (-3475 4150);
FORCEPROP 2 LAST PATH I13
J 0
(-3200 4300);
DISPLAY 0.680851 (-3200 4300);
DISPLAY INVISIBLE (-3200 4300);
FORCEADD OFFPAGE..5
R 2
(-3375 4325);
FORCEPROP 2 LAST $XR0 193 
J 0
(-3186 4325);
DISPLAY 0.638298 (-3186 4325);
PAINT MONO (-3186 4325);
FORCEPROP 2 LAST CDS_LIB standard
J 0
(-3375 4325);
DISPLAY INVISIBLE (-3375 4325);
FORCEPROP 2 LAST BOM_COST SYS_CLOCK
J 2
(-3575 4425);
DISPLAY 0.808511 (-3575 4425);
DISPLAY INVISIBLE (-3575 4425);
FORCEPROP 2 LAST ROOM DB2000_2_NVME
J 2
(-3575 4375);
DISPLAY 0.808511 (-3575 4375);
PAINT RED (-3575 4375);
DISPLAY INVISIBLE (-3575 4375);
FORCEPROP 1 LAST OFFPAGE TRUE
J 2
(-3700 4200);
DISPLAY 0.872340 (-3700 4200);
PAINT GREEN (-3700 4200);
DISPLAY INVISIBLE (-3700 4200);
FORCEPROP 1 LAST COMMENT_BODY TRUE
J 2
(-3475 4250);
DISPLAY 0.872340 (-3475 4250);
PAINT GREEN (-3475 4250);
DISPLAY INVISIBLE (-3475 4250);
FORCEPROP 2 LAST PATH I14
J 0
(-3200 4400);
DISPLAY 0.680851 (-3200 4400);
DISPLAY INVISIBLE (-3200 4400);
FORCEADD SN74LVC2G07DCKR..1
(-4675 4275);
FORCEPROP 1 LAST LOCATION U29
J 0
(-4850 4480);
DISPLAY 0.489362 (-4850 4480);
PAINT SKYBLUE (-4850 4480);
FORCEPROP 2 LAST $SEC 1
J 0
(-4850 4625);
DISPLAY 0.680851 (-4850 4625);
PAINT MONO (-4850 4625);
DISPLAY INVISIBLE (-4850 4625);
FORCEPROP 2 LAST CDS_SEC 1
J 0
(-4850 4625);
DISPLAY 0.680851 (-4850 4625);
DISPLAY INVISIBLE (-4850 4625);
FORCEPROP 2 LASTPIN (-5000 4325) $PN 1
J 2
(-5010 4335);
DISPLAY 0.489362 (-5010 4335);
PAINT MONO (-5010 4335);
FORCEPROP 2 LASTPIN (-4350 4325) $PN 6
J 0
(-4340 4335);
DISPLAY 0.489362 (-4340 4335);
PAINT MONO (-4340 4335);
FORCEPROP 2 LASTPIN (-5000 4225) $PN 3
J 2
(-5010 4235);
DISPLAY 0.489362 (-5010 4235);
PAINT MONO (-5010 4235);
FORCEPROP 2 LASTPIN (-4350 4225) $PN 4
J 0
(-4340 4235);
DISPLAY 0.489362 (-4340 4235);
PAINT MONO (-4340 4235);
FORCEPROP 2 LASTPIN (-5000 4275) $PN 2
J 2
(-5010 4285);
DISPLAY 0.489362 (-5010 4285);
PAINT MONO (-5010 4285);
FORCEPROP 2 LASTPIN (-4350 4275) $PN 5
J 0
(-4340 4285);
DISPLAY 0.489362 (-4340 4285);
PAINT MONO (-4340 4285);
FORCEPROP 1 LAST MATERIAL IC
J 0
(-4850 4385);
DISPLAY 0.489362 (-4850 4385);
PAINT SKYBLUE (-4850 4385);
FORCEPROP 2 LAST VALUE SN74LVC2G07DCKR
J 0
(-4850 4575);
DISPLAY 0.489362 (-4850 4575);
PAINT SKYBLUE (-4850 4575);
FORCEPROP 2 LAST PACK_TYPE SMLF
J 0
(-4850 4525);
DISPLAY 0.489362 (-4850 4525);
PAINT SKYBLUE (-4850 4525);
FORCEPROP 1 LAST NEEDS_NO_SIZE TRUE
J 0
(-4675 4275);
DISPLAY 0.468085 (-4675 4275);
PAINT GREEN (-4675 4275);
DISPLAY INVISIBLE (-4675 4275);
FORCEPROP 2 LAST CDS_LIB pure_quanta
J 0
(-4675 4275);
DISPLAY INVISIBLE (-4675 4275);
FORCEPROP 1 LAST PATH I15
J 0
(-4525 4380);
DISPLAY 0.723404 (-4525 4380);
PAINT GREEN (-4525 4380);
DISPLAY INVISIBLE (-4525 4380);
FORCEPROP 1 LAST PART_NUMBER AL002G07006
J 0
(-4850 4435);
DISPLAY 0.489362 (-4850 4435);
PAINT SKYBLUE (-4850 4435);
DISPLAY INVISIBLE (-4850 4435);
FORCEADD OFFPAGE..5
R 2
(-3325 2550);
FORCEPROP 2 LAST $XR0 210 
J 0
(-3136 2550);
DISPLAY 0.638298 (-3136 2550);
PAINT MONO (-3136 2550);
FORCEPROP 2 LAST BOM_COST SYS_CLOCK
J 2
(-3525 2650);
DISPLAY 0.808511 (-3525 2650);
DISPLAY INVISIBLE (-3525 2650);
FORCEPROP 2 LAST CDS_LIB standard
J 0
(-3325 2550);
DISPLAY INVISIBLE (-3325 2550);
FORCEPROP 2 LAST ROOM DB2000_2_NVME
J 2
(-3525 2600);
DISPLAY 0.808511 (-3525 2600);
PAINT RED (-3525 2600);
DISPLAY INVISIBLE (-3525 2600);
FORCEPROP 1 LAST OFFPAGE TRUE
J 2
(-3650 2425);
DISPLAY 0.872340 (-3650 2425);
PAINT GREEN (-3650 2425);
DISPLAY INVISIBLE (-3650 2425);
FORCEPROP 1 LAST COMMENT_BODY TRUE
J 2
(-3425 2475);
DISPLAY 0.872340 (-3425 2475);
PAINT GREEN (-3425 2475);
DISPLAY INVISIBLE (-3425 2475);
FORCEPROP 2 LAST PATH I16
J 0
(-3150 2625);
DISPLAY 0.680851 (-3150 2625);
DISPLAY INVISIBLE (-3150 2625);
FORCEADD OFFPAGE..5
R 2
(-3325 2450);
FORCEPROP 2 LAST $XR0 217 
J 0
(-3136 2450);
DISPLAY 0.638298 (-3136 2450);
PAINT MONO (-3136 2450);
FORCEPROP 2 LAST BOM_COST SYS_CLOCK
J 2
(-3525 2550);
DISPLAY 0.808511 (-3525 2550);
DISPLAY INVISIBLE (-3525 2550);
FORCEPROP 2 LAST CDS_LIB standard
J 0
(-3325 2450);
DISPLAY INVISIBLE (-3325 2450);
FORCEPROP 2 LAST ROOM DB2000_2_NVME
J 2
(-3525 2500);
DISPLAY 0.808511 (-3525 2500);
PAINT RED (-3525 2500);
DISPLAY INVISIBLE (-3525 2500);
FORCEPROP 1 LAST OFFPAGE TRUE
J 2
(-3650 2325);
DISPLAY 0.872340 (-3650 2325);
PAINT GREEN (-3650 2325);
DISPLAY INVISIBLE (-3650 2325);
FORCEPROP 1 LAST COMMENT_BODY TRUE
J 2
(-3425 2375);
DISPLAY 0.872340 (-3425 2375);
PAINT GREEN (-3425 2375);
DISPLAY INVISIBLE (-3425 2375);
FORCEPROP 2 LAST PATH I17
J 0
(-3150 2525);
DISPLAY 0.680851 (-3150 2525);
DISPLAY INVISIBLE (-3150 2525);
FORCEADD Q_CAP..1
(-4075 2800);
FORCEPROP 1 LAST LOCATION C224
J 0
(-4025 2950);
DISPLAY 0.489362 (-4025 2950);
PAINT SKYBLUE (-4025 2950);
FORCEPROP 2 LAST $SEC 1
J 0
(-4025 3000);
DISPLAY 0.680851 (-4025 3000);
PAINT MONO (-4025 3000);
DISPLAY INVISIBLE (-4025 3000);
FORCEPROP 2 LAST CDS_SEC 1
J 0
(-4025 3000);
DISPLAY 0.680851 (-4025 3000);
DISPLAY INVISIBLE (-4025 3000);
FORCEPROP 1 LASTPIN (-4075 2900) $PN 1
J 0
(-4065 2880);
DISPLAY 0.489362 (-4065 2880);
PAINT MONO (-4065 2880);
FORCEPROP 1 LASTPIN (-4075 2700) $PN 2
J 0
(-4065 2680);
DISPLAY 0.489362 (-4065 2680);
PAINT MONO (-4065 2680);
FORCEPROP 1 LAST MATERIAL X7R
J 0
(-4025 2750);
DISPLAY 0.489362 (-4025 2750);
PAINT SKYBLUE (-4025 2750);
FORCEPROP 1 LAST TOLERANCE 10%
J 0
(-4025 2800);
DISPLAY 0.489362 (-4025 2800);
PAINT SKYBLUE (-4025 2800);
FORCEPROP 1 LAST VALUE 0.1UF
J 0
(-3850 2950);
DISPLAY 0.489362 (-3850 2950);
PAINT SKYBLUE (-3850 2950);
FORCEPROP 1 LAST VOLTAGE 25V
J 0
(-4025 2850);
DISPLAY 0.489362 (-4025 2850);
PAINT SKYBLUE (-4025 2850);
FORCEPROP 1 LAST PACK_TYPE 0402
J 0
(-4025 2700);
DISPLAY 0.489362 (-4025 2700);
PAINT SKYBLUE (-4025 2700);
FORCEPROP 2 LAST CDS_LIB pure_quanta
J 0
(-4075 2800);
DISPLAY INVISIBLE (-4075 2800);
FORCEPROP 1 LAST PATH I19
J 0
(-4025 2950);
DISPLAY 0.978723 (-4025 2950);
PAINT WHITE (-4025 2950);
DISPLAY INVISIBLE (-4025 2950);
FORCEPROP 1 LAST PART_NUMBER CH4104K1B00
J 0
(-4025 2650);
DISPLAY 0.489362 (-4025 2650);
PAINT SKYBLUE (-4025 2650);
DISPLAY INVISIBLE (-4025 2650);
FORCEADD GND..1
(-5900 3675);
FORCEPROP 3 LASTPIN (-5900 3725) SIG_NAME GND\g
J 0
(-5890 3735);
DISPLAY 0.659574 (-5890 3735);
PAINT MONO (-5890 3735);
DISPLAY INVISIBLE (-5890 3735);
FORCEPROP 2 LAST CDS_LIB pure_quanta_power
J 0
(-5900 3675);
DISPLAY INVISIBLE (-5900 3675);
FORCEPROP 1 LAST SIZE 1B
J 0
(-5825 3625);
DISPLAY 0.851064 (-5825 3625);
PAINT GREEN (-5825 3625);
DISPLAY INVISIBLE (-5825 3625);
FORCEPROP 2 LAST BOM_COST MEM
J 0
(-6000 3750);
DISPLAY 0.808511 (-6000 3750);
DISPLAY INVISIBLE (-6000 3750);
FORCEPROP 1 LAST HDL_POWER GND
J 0
(-5900 3825);
DISPLAY 0.851064 (-5900 3825);
PAINT GREEN (-5900 3825);
DISPLAY INVISIBLE (-5900 3825);
FORCEPROP 1 LAST PATH I2
J 0
(-5825 3675);
DISPLAY 0.872340 (-5825 3675);
PAINT AQUA (-5825 3675);
DISPLAY INVISIBLE (-5825 3675);
FORCEADD UNIVERSAL_GND..1
(-4075 2600);
FORCEPROP 3 LASTPIN (-4075 2650) SIG_NAME GND\g
J 0
(-4065 2660);
DISPLAY 0.659574 (-4065 2660);
PAINT MONO (-4065 2660);
DISPLAY INVISIBLE (-4065 2660);
FORCEPROP 2 LAST CDS_LIB pure_quanta_power
J 0
(-4075 2600);
DISPLAY INVISIBLE (-4075 2600);
FORCEPROP 1 LAST HDL_POWER GND
J 1
(-4050 2525);
DISPLAY 0.872340 (-4050 2525);
PAINT GREEN (-4050 2525);
DISPLAY INVISIBLE (-4050 2525);
FORCEPROP 1 LAST PATH I20
J 0
(-4000 2600);
DISPLAY 0.872340 (-4000 2600);
PAINT AQUA (-4000 2600);
DISPLAY INVISIBLE (-4000 2600);
FORCEADD SN74LVC2G07DCKR..1
(-4625 2500);
FORCEPROP 1 LAST LOCATION U40
J 0
(-4800 2705);
DISPLAY 0.489362 (-4800 2705);
PAINT SKYBLUE (-4800 2705);
FORCEPROP 2 LAST $SEC 1
J 0
(-4800 2850);
DISPLAY 0.680851 (-4800 2850);
PAINT MONO (-4800 2850);
DISPLAY INVISIBLE (-4800 2850);
FORCEPROP 2 LAST CDS_SEC 1
J 0
(-4800 2850);
DISPLAY 0.680851 (-4800 2850);
DISPLAY INVISIBLE (-4800 2850);
FORCEPROP 2 LASTPIN (-4950 2550) $PN 1
J 2
(-4960 2560);
DISPLAY 0.489362 (-4960 2560);
PAINT MONO (-4960 2560);
FORCEPROP 2 LASTPIN (-4300 2550) $PN 6
J 0
(-4290 2560);
DISPLAY 0.489362 (-4290 2560);
PAINT MONO (-4290 2560);
FORCEPROP 2 LASTPIN (-4950 2450) $PN 3
J 2
(-4960 2460);
DISPLAY 0.489362 (-4960 2460);
PAINT MONO (-4960 2460);
FORCEPROP 2 LASTPIN (-4300 2450) $PN 4
J 0
(-4290 2460);
DISPLAY 0.489362 (-4290 2460);
PAINT MONO (-4290 2460);
FORCEPROP 2 LASTPIN (-4950 2500) $PN 2
J 2
(-4960 2510);
DISPLAY 0.489362 (-4960 2510);
PAINT MONO (-4960 2510);
FORCEPROP 2 LASTPIN (-4300 2500) $PN 5
J 0
(-4290 2510);
DISPLAY 0.489362 (-4290 2510);
PAINT MONO (-4290 2510);
FORCEPROP 1 LAST MATERIAL IC
J 0
(-4800 2610);
DISPLAY 0.489362 (-4800 2610);
PAINT SKYBLUE (-4800 2610);
FORCEPROP 2 LAST VALUE SN74LVC2G07DCKR
J 0
(-4800 2800);
DISPLAY 0.489362 (-4800 2800);
PAINT SKYBLUE (-4800 2800);
FORCEPROP 2 LAST PACK_TYPE SMLF
J 0
(-4800 2750);
DISPLAY 0.489362 (-4800 2750);
PAINT SKYBLUE (-4800 2750);
FORCEPROP 1 LAST NEEDS_NO_SIZE TRUE
J 0
(-4625 2500);
DISPLAY 0.468085 (-4625 2500);
PAINT GREEN (-4625 2500);
DISPLAY INVISIBLE (-4625 2500);
FORCEPROP 2 LAST CDS_LIB pure_quanta
J 0
(-4625 2500);
DISPLAY INVISIBLE (-4625 2500);
FORCEPROP 1 LAST PATH I21
J 0
(-4475 2605);
DISPLAY 0.723404 (-4475 2605);
PAINT GREEN (-4475 2605);
DISPLAY INVISIBLE (-4475 2605);
FORCEPROP 1 LAST PART_NUMBER AL002G07006
J 0
(-4800 2660);
DISPLAY 0.489362 (-4800 2660);
PAINT SKYBLUE (-4800 2660);
DISPLAY INVISIBLE (-4800 2660);
FORCEADD UNIVERSAL_GND..1
R 5
(-5050 2500);
FORCEPROP 3 LASTPIN (-5000 2500) SIG_NAME GND\g
J 0
(-4990 2510);
DISPLAY 0.659574 (-4990 2510);
PAINT MONO (-4990 2510);
DISPLAY INVISIBLE (-4990 2510);
FORCEPROP 2 LAST CDS_LIB pure_quanta_power
J 0
(-5050 2500);
DISPLAY INVISIBLE (-5050 2500);
FORCEPROP 1 LAST HDL_POWER GND
R 3
J 1
(-5125 2475);
DISPLAY 0.872340 (-5125 2475);
PAINT GREEN (-5125 2475);
DISPLAY INVISIBLE (-5125 2475);
FORCEPROP 1 LAST PATH I22
R 3
J 0
(-5050 2425);
DISPLAY 0.872340 (-5050 2425);
PAINT AQUA (-5050 2425);
DISPLAY INVISIBLE (-5050 2425);
FORCEADD UNIVERSAL_POWER..1
R 2
(-4150 3125);
FORCEPROP 3 LASTPIN (-4150 3075) SIG_NAME P1V8_AUX\g
J 0
(-4140 3085);
DISPLAY 0.659574 (-4140 3085);
PAINT MONO (-4140 3085);
DISPLAY INVISIBLE (-4140 3085);
FORCEPROP 1 LAST HDL_POWER P1V8_AUX
J 1
(-4150 3175);
DISPLAY 0.489362 (-4150 3175);
PAINT GREEN (-4150 3175);
FORCEPROP 2 LAST CDS_LIB pure_quanta_power
J 0
(-4150 3125);
DISPLAY INVISIBLE (-4150 3125);
FORCEPROP 1 LAST PATH I23
J 2
(-4200 3150);
DISPLAY 0.872340 (-4200 3150);
PAINT AQUA (-4200 3150);
DISPLAY INVISIBLE (-4200 3150);
FORCEADD OFFPAGE..1
(-6000 4325);
FORCEPROP 2 LAST $XR2 85 
J 0
(-6431 4325);
DISPLAY 0.638298 (-6431 4325);
PAINT MONO (-6431 4325);
FORCEPROP 2 LAST $XR1 81 
J 0
(-6341 4325);
DISPLAY 0.638298 (-6341 4325);
PAINT MONO (-6341 4325);
FORCEPROP 2 LAST $XR0 28 
J 0
(-6251 4325);
DISPLAY 0.638298 (-6251 4325);
PAINT MONO (-6251 4325);
FORCEPROP 2 LAST CDS_LIB standard
J 0
(-6000 4325);
DISPLAY INVISIBLE (-6000 4325);
FORCEPROP 1 LAST OFFPAGE TRUE
J 0
(-5675 4200);
DISPLAY 0.872340 (-5675 4200);
PAINT GREEN (-5675 4200);
DISPLAY INVISIBLE (-5675 4200);
FORCEPROP 1 LAST COMMENT_BODY TRUE
J 0
(-5875 4225);
DISPLAY 0.872340 (-5875 4225);
PAINT GREEN (-5875 4225);
DISPLAY INVISIBLE (-5875 4225);
FORCEPROP 2 LAST PATH I3
J 0
(-6200 4375);
DISPLAY 0.680851 (-6200 4375);
DISPLAY INVISIBLE (-6200 4375);
FORCEADD OFFPAGE..1
(-5950 2550);
FORCEPROP 2 LAST $XR2 85 
J 0
(-6351 2550);
DISPLAY 0.638298 (-6351 2550);
PAINT MONO (-6351 2550);
FORCEPROP 2 LAST $XR1 81 
J 0
(-6261 2550);
DISPLAY 0.638298 (-6261 2550);
PAINT MONO (-6261 2550);
FORCEPROP 2 LAST $XR0 55 
J 0
(-6171 2550);
DISPLAY 0.638298 (-6171 2550);
PAINT MONO (-6171 2550);
FORCEPROP 2 LAST CDS_LIB standard
J 0
(-5950 2550);
DISPLAY INVISIBLE (-5950 2550);
FORCEPROP 1 LAST OFFPAGE TRUE
J 0
(-5625 2425);
DISPLAY 0.872340 (-5625 2425);
PAINT GREEN (-5625 2425);
DISPLAY INVISIBLE (-5625 2425);
FORCEPROP 1 LAST COMMENT_BODY TRUE
J 0
(-5825 2450);
DISPLAY 0.872340 (-5825 2450);
PAINT GREEN (-5825 2450);
DISPLAY INVISIBLE (-5825 2450);
FORCEPROP 2 LAST PATH I4
J 0
(-5900 2625);
DISPLAY 0.680851 (-5900 2625);
DISPLAY INVISIBLE (-5900 2625);
FORCEADD Q_RES..2
R 2
(-5850 2175);
FORCEPROP 1 LAST LOCATION R703
J 2
(-5895 2300);
DISPLAY 0.489362 (-5895 2300);
PAINT SKYBLUE (-5895 2300);
FORCEPROP 2 LAST $SEC 1
J 0
(-5900 2400);
DISPLAY 0.680851 (-5900 2400);
PAINT MONO (-5900 2400);
DISPLAY INVISIBLE (-5900 2400);
FORCEPROP 2 LAST CDS_SEC 1
J 0
(-5900 2400);
DISPLAY 0.680851 (-5900 2400);
DISPLAY INVISIBLE (-5900 2400);
FORCEPROP 1 LASTPIN (-5850 2275) $PN 1
J 2
(-5855 2237);
DISPLAY 0.489362 (-5855 2237);
PAINT MONO (-5855 2237);
FORCEPROP 1 LASTPIN (-5850 2075) $PN 2
J 2
(-5855 2085);
DISPLAY 0.489362 (-5855 2085);
PAINT MONO (-5855 2085);
FORCEPROP 1 LAST PACK_TYPE 0402LF
J 2
(-5890 2075);
DISPLAY 0.489362 (-5890 2075);
PAINT SKYBLUE (-5890 2075);
FORCEPROP 1 LAST VALUE 10K
J 2
(-5895 2275);
DISPLAY 0.489362 (-5895 2275);
PAINT SKYBLUE (-5895 2275);
FORCEPROP 1 LAST TOLERANCE 5%
J 2
(-5895 2225);
DISPLAY 0.489362 (-5895 2225);
PAINT SKYBLUE (-5895 2225);
FORCEPROP 1 LAST MATERIAL EMPTY
J 2
(-5890 2125);
DISPLAY 0.489362 (-5890 2125);
PAINT RED (-5890 2125);
FORCEPROP 1 LAST WATTAGE 1/16W
J 2
(-5890 2175);
DISPLAY 0.489362 (-5890 2175);
PAINT SKYBLUE (-5890 2175);
FORCEPROP 2 LAST CDS_LIB pure_quanta
J 0
(-5850 2175);
DISPLAY INVISIBLE (-5850 2175);
FORCEPROP 1 LAST PATH I5
J 2
(-5900 2350);
DISPLAY 0.978723 (-5900 2350);
PAINT WHITE (-5900 2350);
DISPLAY INVISIBLE (-5900 2350);
FORCEPROP 1 LAST PART_NUMBER CS31002JB08
J 2
(-5900 2025);
DISPLAY 0.489362 (-5900 2025);
PAINT SKYBLUE (-5900 2025);
DISPLAY INVISIBLE (-5900 2025);
FORCEADD GND..1
(-5850 1900);
FORCEPROP 3 LASTPIN (-5850 1950) SIG_NAME GND\g
J 0
(-5840 1960);
DISPLAY 0.659574 (-5840 1960);
PAINT MONO (-5840 1960);
DISPLAY INVISIBLE (-5840 1960);
FORCEPROP 1 LAST SIZE 1B
J 0
(-5775 1850);
DISPLAY 0.851064 (-5775 1850);
PAINT GREEN (-5775 1850);
DISPLAY INVISIBLE (-5775 1850);
FORCEPROP 2 LAST BOM_COST MEM
J 0
(-5950 1975);
DISPLAY 0.808511 (-5950 1975);
DISPLAY INVISIBLE (-5950 1975);
FORCEPROP 2 LAST CDS_LIB pure_quanta_power
J 0
(-5850 1900);
DISPLAY INVISIBLE (-5850 1900);
FORCEPROP 1 LAST HDL_POWER GND
J 0
(-5850 2050);
DISPLAY 0.851064 (-5850 2050);
PAINT GREEN (-5850 2050);
DISPLAY INVISIBLE (-5850 2050);
FORCEPROP 1 LAST PATH I6
J 0
(-5775 1900);
DISPLAY 0.872340 (-5775 1900);
PAINT AQUA (-5775 1900);
DISPLAY INVISIBLE (-5775 1900);
FORCEADD UNIVERSAL_GND..1
R 5
(-5100 4275);
FORCEPROP 3 LASTPIN (-5050 4275) SIG_NAME GND\g
J 0
(-5040 4285);
DISPLAY 0.659574 (-5040 4285);
PAINT MONO (-5040 4285);
DISPLAY INVISIBLE (-5040 4285);
FORCEPROP 2 LAST CDS_LIB pure_quanta_power
J 0
(-5100 4275);
DISPLAY INVISIBLE (-5100 4275);
FORCEPROP 1 LAST HDL_POWER GND
R 3
J 1
(-5175 4250);
DISPLAY 0.872340 (-5175 4250);
PAINT GREEN (-5175 4250);
DISPLAY INVISIBLE (-5175 4250);
FORCEPROP 1 LAST PATH I9
R 3
J 0
(-5100 4200);
DISPLAY 0.872340 (-5100 4200);
PAINT AQUA (-5100 4200);
DISPLAY INVISIBLE (-5100 4200);
FORCEADD DNS..2
(-5900 3875);
PAINT RED (-5900 3875);
FORCEPROP 2 LAST CDS_LIB mstr_misc
J 0
(-5900 3875);
DISPLAY INVISIBLE (-5900 3875);
FORCEPROP 1 LAST COMMENT_BODY TRUE
J 0
(-5900 3875);
PAINT RED (-5900 3875);
DISPLAY INVISIBLE (-5900 3875);
FORCEADD DNS..2
(-5825 2100);
PAINT RED (-5825 2100);
FORCEPROP 2 LAST CDS_LIB mstr_misc
J 0
(-5825 2100);
DISPLAY INVISIBLE (-5825 2100);
FORCEPROP 1 LAST COMMENT_BODY TRUE
J 0
(-5825 2100);
PAINT RED (-5825 2100);
DISPLAY INVISIBLE (-5825 2100);
FORCEADD QUANTA_TITLE_BLOCK_C..1
(0 0);
FORCEPROP 0 LAST CDS_CON_LAST_MODIFIED Thu Sep 14 16:12:05 2023
J 0
(-1885 15);
DISPLAY INVISIBLE (-1885 15);
FORCEPROP 1 LAST CUSTOM_TXT_CDS <CON_LAST_MODIFIED>
J 0
(-1885 15);
DISPLAY 0.978723 (-1885 15);
FORCEPROP 2 LAST CUSTOM_TXT_CDS <XR_PAGE_TITLE>
J 0
(-7890 5250);
DISPLAY 0.638298 (-7890 5250);
PAINT PINK (-7890 5250);
DISPLAY INVISIBLE (-7890 5250);
FORCEPROP 1 LAST CUSTOM_TXT_CDS <NAME_2>
J 0
(-3175 50);
FORCEPROP 1 LAST CUSTOM_TXT_CDS <NAME_1>
J 0
(-3175 175);
FORCEPROP 1 LAST CUSTOM_TXT_CDS <Q_NUMBER>
J 0
(-1403 103);
DISPLAY 1.212766 (-1403 103);
FORCEPROP 1 LAST CUSTOM_TXT_CDS <Q_PROJ>
J 0
(-2382 102);
DISPLAY 1.212766 (-2382 102);
FORCEPROP 1 LAST CUSTOM_TXT_CDS <Q_REV>
J 0
(-184 103);
DISPLAY 1.212766 (-184 103);
FORCEPROP 1 LAST CUSTOM_TXT_CDS <CON_PAGE_NUM> OF <CON_TOTAL_PAGES>
J 0
(-446 18);
DISPLAY 0.978723 (-446 18);
FORCEPROP 1 LAST Q_TITLE CPU PWROK
J 0
(-9300 50);
DISPLAY 2.446809 (-9300 50);
PAINT GREEN (-9300 50);
FORCEPROP 1 LAST CDS_LMAN_SYM_OUTLINE -9475,6775,100,-125
J 0
(0 0);
DISPLAY 0.468085 (0 0);
PAINT GREEN (0 0);
DISPLAY INVISIBLE (0 0);
FORCEPROP 2 LAST CDS_LIB pure_quanta
J 0
(0 0);
DISPLAY INVISIBLE (0 0);
FORCEPROP 2 LAST PAGE_BORDER TRUE
J 0
(-7890 5250);
DISPLAY 0.638298 (-7890 5250);
PAINT PINK (-7890 5250);
DISPLAY INVISIBLE (-7890 5250);
FORCEPROP 2 LAST CDS_XR_PAGE_TITLE CR-78 : @T6G_MB_LIB.T6G(SCH_1):PAGE78
J 0
(-7890 5250);
DISPLAY 0.638298 (-7890 5250);
PAINT PINK (-7890 5250);
DISPLAY INVISIBLE (-7890 5250);
FORCEPROP 1 LAST Q_DEPT BU9
J 1
(-3763 49);
DISPLAY 1.957447 (-3763 49);
PAINT GREEN (-3763 49);
DISPLAY INVISIBLE (-3763 49);
FORCEPROP 1 LAST COMMENT_BODY TRUE
J 0
(12 -13);
DISPLAY 0.978723 (12 -13);
PAINT GREEN (12 -13);
DISPLAY INVISIBLE (12 -13);
WIRE 16 -1 (-4125 4475)(-4125 4425);
WIRE 16 -1 (-5900 3850)(-5900 3725);
WIRE 16 -1 (-4075 2700)(-4075 2650);
WIRE 16 -1 (-5000 2500)(-4950 2500);
WIRE 16 -1 (-5850 2075)(-5850 1950);
WIRE 16 -1 (-5050 4275)(-5000 4275);
WIRE 16 -1 (-5850 2550)(-5225 2550);
WIRE 16 -1 (-5850 2275)(-5850 2550);
FORCEPROP 2 LAST SIG_NAME PWRGD_CPU1_PWROK
J 0
(-5810 2560);
DISPLAY 0.489362 (-5810 2560);
WIRE 16 -1 (-5850 2550)(-5900 2550);
WIRE 16 -1 (-5225 2550)(-4950 2550);
WIRE 16 -1 (-5225 2550)(-5225 2450);
WIRE 16 -1 (-5225 2450)(-4950 2450);
WIRE 16 -1 (-5900 4050)(-5900 4325);
FORCEPROP 2 LAST SIG_NAME PWRGD_CPU0_PWROK
J 0
(-5910 4335);
DISPLAY 0.489362 (-5910 4335);
WIRE 16 -1 (-5275 4325)(-5900 4325);
WIRE 16 -1 (-5900 4325)(-5950 4325);
WIRE 16 -1 (-5000 4325)(-5275 4325);
WIRE 16 -1 (-5275 4325)(-5275 4225);
WIRE 16 -1 (-5275 4225)(-5000 4225);
WIRE 16 -1 (-3425 4325)(-4350 4325);
FORCEPROP 2 LAST SIG_NAME PVDDCR_CPU0_P0_RESET_N
J 0
(-4060 4335);
DISPLAY 0.489362 (-4060 4335);
WIRE 16 -1 (-3425 4225)(-4350 4225);
FORCEPROP 2 LAST SIG_NAME PVDDCR_CPU1_P0_RESET_N
J 0
(-4060 4235);
DISPLAY 0.489362 (-4060 4235);
WIRE 16 -1 (-4075 2900)(-4075 2975);
WIRE 16 -1 (-4075 2975)(-4150 2975);
WIRE 16 -1 (-4150 3075)(-4150 2975);
WIRE 16 -1 (-4150 2975)(-4150 2500);
WIRE 16 -1 (-4300 2500)(-4150 2500);
WIRE 16 -1 (-4125 4675)(-4125 4750);
WIRE 16 -1 (-4125 4750)(-4200 4750);
WIRE 16 -1 (-4200 4850)(-4200 4750);
WIRE 16 -1 (-4200 4750)(-4200 4275);
WIRE 16 -1 (-4350 4275)(-4200 4275);
WIRE 16 -1 (-4300 2550)(-3375 2550);
FORCEPROP 2 LAST SIG_NAME PVDDCR_CPU0_P1_RESET_N
J 0
(-3885 2560);
DISPLAY 0.489362 (-3885 2560);
WIRE 16 -1 (-4300 2450)(-3375 2450);
FORCEPROP 2 LAST SIG_NAME PVDDCR_CPU1_P1_RESET_N
J 0
(-3885 2460);
DISPLAY 0.489362 (-3885 2460);
DOT 1 (-4150 2975);
DOT 1 (-4200 4750);
DOT 1 (-5275 4325);
DOT 1 (-5900 4325);
DOT 1 (-5225 2550);
DOT 1 (-5850 2550);
FORCENOTE
VID:VDDCR_CPU*/VDDCR_SOC/VDDIO
(-8025 5600) 0;
DISPLAY LEFT (-8025 5600);
DISPLAY 5.170213 (-8025 5600);
PAINT WHITE (-8025 5600);
FORCENOTE
PWROK TO VR RST
(-8025 5950) 0;
DISPLAY LEFT (-8025 5950);
DISPLAY 5.170213 (-8025 5950);
PAINT WHITE (-8025 5950);
QUIT
